FILE_TYPE = CONNECTIVITY;
{Allegro Design Entry HDL 16.6-p007 (v16-6-112F) 10/10/2012}
"PAGE_NUMBER" = 166;
0"NC";
1"PVCCIO_CPU0\g";
2"GND\g";
3"PECI_CPU_G";
4"PECI_BMC";
5"PECI_PCH";
%"RES"
"1","(-4550,3125)","0","mstr_discrete","I11";
;
CDS_SEC"1"
SEC_TYPE"0402"
SEC"1"
BOM_COST"DEBUG"
ROOM"PECI"
CDS_LOCATION"R7C18"
CDS_LIB"mstr_discrete"
TOLERANCE"5%"
LOCATION"R7C18"
VALUE"0.0"
MATERIAL"EMPTY"
PACK_TYPE"0402"
PART_NUMBER"G21497-005"
WATTAGE"1/16W";
"B"
$PN"2"3;
"A"
$PN"1"4;
%"RES"
"2","(-4850,3500)","0","mstr_discrete","I14";
;
CDS_SEC"1"
SEC_TYPE"0402"
BOM_COST"DEBUG"
SEC"1"
ROOM"PECI"
CDS_LOCATION"R7C22"
CDS_LIB"mstr_discrete"
PART_NUMBER"G21796-072"
LOCATION"R7C22"
VALUE"4.75K"
MATERIAL"EMPTY"
WATTAGE"1/16W"
TOLERANCE"1%"
PACK_TYPE"0402";
"A"
$PN"1"1;
"B"
$PN"2"5;
%"RES"
"1","(-4675,2525)","0","mstr_discrete","I15";
;
CDS_SEC"1"
SEC"1"
BOM_COST"DEBUG"
SEC_TYPE"0402"
ROOM"PECI"
CDS_LOCATION"R7C19"
CDS_LIB"mstr_discrete"
TOLERANCE"5%"
LOCATION"R7C19"
PART_NUMBER"G21497-005"
PACK_TYPE"0402"
MATERIAL"CHIP"
WATTAGE"1/16W"
VALUE"0.0";
"B"
$PN"2"3;
"A"
$PN"1"5;
%"RES"
"2","(-5050,3500)","2","mstr_discrete","I28";
;
CDS_SEC"1"
BOM_COST"DEBUG"
SEC_TYPE"0402"
SEC"1"
CDS_LOCATION"R7C17"
ROOM"PECI"
CDS_LIB"mstr_discrete"
LOCATION"R7C17"
PART_NUMBER"G21796-072"
VALUE"4.75K"
TOLERANCE"1%"
PACK_TYPE"0402"
MATERIAL"CHIP"
WATTAGE"1/16W";
"A"
$PN"1"1;
"B"
$PN"2"4;
%"PVCCIO_CPU0"
"1","(-4850,3775)","0","mstr_symbols","I31";
;
HDL_POWER"PVCCIO_CPU0"
CDS_LIB"mstr_symbols"
BODY_TYPE"PLUMBING"
VOLTAGE"1.1V";
"G\NAC"1;
%"RES"
"2","(-4475,2200)","0","mstr_discrete","I32";
;
CDS_SEC"1"
BOM_COST"DEBUG"
SEC_TYPE"0402"
SEC"1"
CDS_LOCATION"R7D15"
ROOM"PECI"
CDS_LIB"mstr_discrete"
LOCATION"R7D15"
PART_NUMBER"G21796-340"
VALUE"348"
MATERIAL"CHIP"
WATTAGE"1/16W"
TOLERANCE"1%"
PACK_TYPE"0402";
"A"
$PN"1"3;
"B"
$PN"2"2;
%"GND"
"1","(-4475,1950)","0","mstr_symbols","I33";
;
HDL_POWER"GND"
VOLTAGE"0.0V"
CDS_LIB"mstr_symbols"
SIZE"1B"
BODY_TYPE"PLUMBING";
"A\NAC"2;
END.
